(kicad_pcb
	(version 20260206)
	(generator "pcbnew")
	(generator_version "10.0")
	(general
		(thickness 1.6)
		(legacy_teardrops no)
	)
	(paper "A4")
	(title_block
		(title "v1-chassis-manager — T6M_CM_d_v01_1031_1645.brd")
		(comment 1 "Open CloudServer (Microsoft) / footprints 2184-2193 of 2512")
	)
	(layers
		(0 "F.Cu" signal "TOP")
		(4 "In1.Cu" signal "GND1")
		(6 "In2.Cu" signal "IN1")
		(8 "In3.Cu" signal "VCC1")
		(10 "In4.Cu" signal "VCC2")
		(12 "In5.Cu" signal "GND2")
		(14 "In6.Cu" signal "IN2")
		(16 "In7.Cu" signal "IN3")
		(18 "In8.Cu" signal "GND3")
		(2 "B.Cu" signal "BOTTOM")
		(9 "F.Adhes" user "F.Adhesive")
		(11 "B.Adhes" user "B.Adhesive")
		(13 "F.Paste" user "Package Geometry/Pastemask Top")
		(15 "B.Paste" user "Package Geometry/Pastemask Bottom")
		(5 "F.SilkS" user "Ref Des/Silkscreen Top")
		(7 "B.SilkS" user "Ref Des/Silkscreen Bottom")
		(1 "F.Mask" user "Board Geometry/Soldermask Top")
		(3 "B.Mask" user "Board Geometry/Soldermask Bottom")
		(17 "Dwgs.User" user "User.Drawings")
		(19 "Cmts.User" user "User.Comments")
		(21 "Eco1.User" user "User.Eco1")
		(23 "Eco2.User" user "User.Eco2")
		(25 "Edge.Cuts" user "Board Geometry/Outline")
		(27 "Margin" user)
		(31 "F.CrtYd" user "Package Geometry/Place Bound Top")
		(29 "B.CrtYd" user "Package Geometry/Place Bound Bottom")
		(35 "F.Fab" user "Ref Des/Assembly Top")
		(33 "B.Fab" user "Ref Des/Assembly Bottom")
	)
	(footprint ""
		(layer "B.Cu")
		(at 47.74438 -97.104454 -90)
		(property "Reference" "R124"
			(at -0.960374 -0.484378 270)
			(unlocked yes)
			(layer "B.SilkS")
			(effects
				(font
					(size 0.7874 0.5842)
					(thickness 0.1524)
				)
				(justify left mirror)
			)
		)
		(property "Value" ""
			(at 0 0 90)
			(layer "B.Fab")
			(effects
				(font
					(size 1.27 1.27)
				)
				(justify mirror)
			)
		)
		(duplicate_pad_numbers_are_jumpers no)
		(fp_line
			(start -0.7874 0.4064)
			(end 0.7874 0.4064)
			(stroke
				(width 0.1524)
				(type default)
			)
			(layer "B.SilkS")
		)
		(fp_line
			(start 0.7874 0.4064)
			(end 0.7874 -0.4064)
			(stroke
				(width 0.1524)
				(type default)
			)
			(layer "B.SilkS")
		)
		(fp_line
			(start -0.7874 -0.4064)
			(end -0.7874 0.4064)
			(stroke
				(width 0.1524)
				(type default)
			)
			(layer "B.SilkS")
		)
		(fp_line
			(start 0.7874 -0.4064)
			(end -0.7874 -0.4064)
			(stroke
				(width 0.1524)
				(type default)
			)
			(layer "B.SilkS")
		)
		(fp_poly
			(pts
				(xy 0.508 0.2794) (xy 0.508 0.2286) (xy 0.635 0.2286) (xy 0.635 -0.254) (xy 0.5334 -0.254) (xy 0.5334 -0.2794)
				(xy -0.5334 -0.2794) (xy -0.5334 -0.254) (xy -0.635 -0.254) (xy -0.635 0.254) (xy -0.5334 0.254)
				(xy -0.5334 0.2794)
			)
			(stroke
				(width 0)
				(type default)
			)
			(fill no)
			(layer "B.CrtYd")
		)
		(pad "1" smd rect
			(at -0.40005 0 90)
			(size 0.4572 0.508)
			(layers "B.Cu" "B.Mask" "B.Paste")
			(net "P3V3_NODE1")
		)
		(pad "2" smd rect
			(at 0.40005 0 90)
			(size 0.4572 0.508)
			(layers "B.Cu" "B.Mask" "B.Paste")
			(net "SMB_CPU_NODE1_XDP_DAT")
		)
	)
	(footprint ""
		(layer "B.Cu")
		(at 121.40184 -142.404592 180)
		(property "Reference" "C188"
			(at 2.075942 -0.005334 0)
			(unlocked yes)
			(layer "B.SilkS")
			(effects
				(font
					(size 0.7874 0.5842)
					(thickness 0.1524)
				)
				(justify left mirror)
			)
		)
		(property "Value" ""
			(at 0 0 0)
			(layer "B.Fab")
			(effects
				(font
					(size 1.27 1.27)
				)
				(justify mirror)
			)
		)
		(duplicate_pad_numbers_are_jumpers no)
		(fp_line
			(start 0.7874 0.4064)
			(end 0.7874 -0.4064)
			(stroke
				(width 0.1524)
				(type default)
			)
			(layer "B.SilkS")
		)
		(fp_line
			(start 0.7874 -0.4064)
			(end -0.7874 -0.4064)
			(stroke
				(width 0.1524)
				(type default)
			)
			(layer "B.SilkS")
		)
		(fp_line
			(start 0 0.381)
			(end 0 -0.381)
			(stroke
				(width 0.1524)
				(type default)
			)
			(layer "B.SilkS")
		)
		(fp_line
			(start -0.7874 0.4064)
			(end 0.7874 0.4064)
			(stroke
				(width 0.1524)
				(type default)
			)
			(layer "B.SilkS")
		)
		(fp_line
			(start -0.7874 -0.4064)
			(end -0.7874 0.4064)
			(stroke
				(width 0.1524)
				(type default)
			)
			(layer "B.SilkS")
		)
		(fp_poly
			(pts
				(xy 0.5334 0.254) (xy 0.635 0.254) (xy 0.635 0.2286) (xy 0.635 -0.254) (xy 0.5334 -0.254) (xy 0.5334 -0.2794)
				(xy -0.5334 -0.2794) (xy -0.5334 -0.254) (xy -0.635 -0.254) (xy -0.635 0.254) (xy -0.5334 0.254)
				(xy -0.5334 0.2794) (xy 0.508 0.2794) (xy 0.5334 0.2794)
			)
			(stroke
				(width 0)
				(type default)
			)
			(fill no)
			(layer "B.CrtYd")
		)
		(pad "1" smd rect
			(at -0.40005 0)
			(size 0.4572 0.508)
			(layers "B.Cu" "B.Mask" "B.Paste")
			(net "P2E_CPU_BMC_NODE1_TX_C_DN")
		)
		(pad "2" smd rect
			(at 0.40005 0)
			(size 0.4572 0.508)
			(layers "B.Cu" "B.Mask" "B.Paste")
			(net "P2E_CPU_BMC_NODE1_TX_DN")
		)
	)
	(footprint ""
		(layer "B.Cu")
		(at 35.847274 -67.576192 180)
		(property "Reference" "C17"
			(at 2.062734 -0.060452 0)
			(unlocked yes)
			(layer "B.SilkS")
			(effects
				(font
					(size 0.7874 0.5842)
					(thickness 0.1524)
				)
				(justify left mirror)
			)
		)
		(property "Value" ""
			(at 0 0 0)
			(layer "B.Fab")
			(effects
				(font
					(size 1.27 1.27)
				)
				(justify mirror)
			)
		)
		(duplicate_pad_numbers_are_jumpers no)
		(fp_line
			(start 0.7874 0.4064)
			(end 0.7874 -0.4064)
			(stroke
				(width 0.1524)
				(type default)
			)
			(layer "B.SilkS")
		)
		(fp_line
			(start 0.7874 -0.4064)
			(end -0.7874 -0.4064)
			(stroke
				(width 0.1524)
				(type default)
			)
			(layer "B.SilkS")
		)
		(fp_line
			(start 0 0.381)
			(end 0 -0.381)
			(stroke
				(width 0.1524)
				(type default)
			)
			(layer "B.SilkS")
		)
		(fp_line
			(start -0.7874 0.4064)
			(end 0.7874 0.4064)
			(stroke
				(width 0.1524)
				(type default)
			)
			(layer "B.SilkS")
		)
		(fp_line
			(start -0.7874 -0.4064)
			(end -0.7874 0.4064)
			(stroke
				(width 0.1524)
				(type default)
			)
			(layer "B.SilkS")
		)
		(fp_poly
			(pts
				(xy 0.5334 0.254) (xy 0.635 0.254) (xy 0.635 0.2286) (xy 0.635 -0.254) (xy 0.5334 -0.254) (xy 0.5334 -0.2794)
				(xy -0.5334 -0.2794) (xy -0.5334 -0.254) (xy -0.635 -0.254) (xy -0.635 0.254) (xy -0.5334 0.254)
				(xy -0.5334 0.2794) (xy 0.508 0.2794) (xy 0.5334 0.2794)
			)
			(stroke
				(width 0)
				(type default)
			)
			(fill no)
			(layer "B.CrtYd")
		)
		(pad "1" smd rect
			(at -0.40005 0)
			(size 0.4572 0.508)
			(layers "B.Cu" "B.Mask" "B.Paste")
			(net "P2E_CPU_NIC2_NODE1_TX_C_DP")
		)
		(pad "2" smd rect
			(at 0.40005 0)
			(size 0.4572 0.508)
			(layers "B.Cu" "B.Mask" "B.Paste")
			(net "P2E_CPU_NIC2_NODE1_TX_DP")
		)
	)
	(footprint ""
		(layer "B.Cu")
		(at 156.83738 -156.957522)
		(property "Reference" "C466"
			(at -3.502406 -0.096012 0)
			(unlocked yes)
			(layer "B.SilkS")
			(effects
				(font
					(size 0.7874 0.5842)
					(thickness 0.1524)
				)
				(justify left mirror)
			)
		)
		(property "Value" ""
			(at 0 0 0)
			(layer "B.Fab")
			(effects
				(font
					(size 1.27 1.27)
				)
				(justify mirror)
			)
		)
		(duplicate_pad_numbers_are_jumpers no)
		(fp_line
			(start -0.7874 -0.4064)
			(end -0.7874 0.4064)
			(stroke
				(width 0.1524)
				(type default)
			)
			(layer "B.SilkS")
		)
		(fp_line
			(start -0.7874 0.4064)
			(end 0.7874 0.4064)
			(stroke
				(width 0.1524)
				(type default)
			)
			(layer "B.SilkS")
		)
		(fp_line
			(start 0 0.381)
			(end 0 -0.381)
			(stroke
				(width 0.1524)
				(type default)
			)
			(layer "B.SilkS")
		)
		(fp_line
			(start 0.7874 -0.4064)
			(end -0.7874 -0.4064)
			(stroke
				(width 0.1524)
				(type default)
			)
			(layer "B.SilkS")
		)
		(fp_line
			(start 0.7874 0.4064)
			(end 0.7874 -0.4064)
			(stroke
				(width 0.1524)
				(type default)
			)
			(layer "B.SilkS")
		)
		(fp_poly
			(pts
				(xy 0.5334 0.254) (xy 0.635 0.254) (xy 0.635 0.2286) (xy 0.635 -0.254) (xy 0.5334 -0.254) (xy 0.5334 -0.2794)
				(xy -0.5334 -0.2794) (xy -0.5334 -0.254) (xy -0.635 -0.254) (xy -0.635 0.254) (xy -0.5334 0.254)
				(xy -0.5334 0.2794) (xy 0.508 0.2794) (xy 0.5334 0.2794)
			)
			(stroke
				(width 0)
				(type default)
			)
			(fill no)
			(layer "B.CrtYd")
		)
		(pad "1" smd rect
			(at -0.40005 0 180)
			(size 0.4572 0.508)
			(layers "B.Cu" "B.Mask" "B.Paste")
			(net "P1V05_LAN2")
		)
		(pad "2" smd rect
			(at 0.40005 0 180)
			(size 0.4572 0.508)
			(layers "B.Cu" "B.Mask" "B.Paste")
			(net "GND")
		)
	)
	(footprint ""
		(layer "B.Cu")
		(at 149.390354 -178.784504 90)
		(property "Reference" "R741"
			(at -0.32004 2.22631 270)
			(unlocked yes)
			(layer "B.SilkS")
			(effects
				(font
					(size 0.7874 0.5842)
					(thickness 0.1524)
				)
				(justify left mirror)
			)
		)
		(property "Value" ""
			(at 0 0 90)
			(layer "B.Fab")
			(effects
				(font
					(size 1.27 1.27)
				)
				(justify mirror)
			)
		)
		(duplicate_pad_numbers_are_jumpers no)
		(fp_line
			(start 0.7874 -0.4064)
			(end -0.7874 -0.4064)
			(stroke
				(width 0.1524)
				(type default)
			)
			(layer "B.SilkS")
		)
		(fp_line
			(start -0.7874 -0.4064)
			(end -0.7874 0.4064)
			(stroke
				(width 0.1524)
				(type default)
			)
			(layer "B.SilkS")
		)
		(fp_line
			(start 0.7874 0.4064)
			(end 0.7874 -0.4064)
			(stroke
				(width 0.1524)
				(type default)
			)
			(layer "B.SilkS")
		)
		(fp_line
			(start -0.7874 0.4064)
			(end 0.7874 0.4064)
			(stroke
				(width 0.1524)
				(type default)
			)
			(layer "B.SilkS")
		)
		(fp_poly
			(pts
				(xy 0.508 0.2794) (xy 0.508 0.2286) (xy 0.635 0.2286) (xy 0.635 -0.254) (xy 0.5334 -0.254) (xy 0.5334 -0.2794)
				(xy -0.5334 -0.2794) (xy -0.5334 -0.254) (xy -0.635 -0.254) (xy -0.635 0.254) (xy -0.5334 0.254)
				(xy -0.5334 0.2794)
			)
			(stroke
				(width 0)
				(type default)
			)
			(fill no)
			(layer "B.CrtYd")
		)
		(pad "1" smd rect
			(at -0.40005 0 270)
			(size 0.4572 0.508)
			(layers "B.Cu" "B.Mask" "B.Paste")
			(net "T11_NODE1_EN")
		)
		(pad "2" smd rect
			(at 0.40005 0 270)
			(size 0.4572 0.508)
			(layers "B.Cu" "B.Mask" "B.Paste")
			(net "P5V_NODE1")
		)
	)
	(footprint ""
		(layer "B.Cu")
		(at 163.128452 -103.094282 180)
		(property "Reference" "C386"
			(at -4.541012 -0.07366 0)
			(unlocked yes)
			(layer "B.SilkS")
			(effects
				(font
					(size 0.7874 0.5842)
					(thickness 0.1524)
				)
				(justify left mirror)
			)
		)
		(property "Value" ""
			(at 0 0 0)
			(layer "B.Fab")
			(effects
				(font
					(size 1.27 1.27)
				)
				(justify mirror)
			)
		)
		(duplicate_pad_numbers_are_jumpers no)
		(fp_line
			(start 0.7874 0.4064)
			(end 0.7874 -0.4064)
			(stroke
				(width 0.1524)
				(type default)
			)
			(layer "B.SilkS")
		)
		(fp_line
			(start 0.7874 -0.4064)
			(end -0.7874 -0.4064)
			(stroke
				(width 0.1524)
				(type default)
			)
			(layer "B.SilkS")
		)
		(fp_line
			(start 0 0.381)
			(end 0 -0.381)
			(stroke
				(width 0.1524)
				(type default)
			)
			(layer "B.SilkS")
		)
		(fp_line
			(start -0.7874 0.4064)
			(end 0.7874 0.4064)
			(stroke
				(width 0.1524)
				(type default)
			)
			(layer "B.SilkS")
		)
		(fp_line
			(start -0.7874 -0.4064)
			(end -0.7874 0.4064)
			(stroke
				(width 0.1524)
				(type default)
			)
			(layer "B.SilkS")
		)
		(fp_poly
			(pts
				(xy 0.5334 0.254) (xy 0.635 0.254) (xy 0.635 0.2286) (xy 0.635 -0.254) (xy 0.5334 -0.254) (xy 0.5334 -0.2794)
				(xy -0.5334 -0.2794) (xy -0.5334 -0.254) (xy -0.635 -0.254) (xy -0.635 0.254) (xy -0.5334 0.254)
				(xy -0.5334 0.2794) (xy 0.508 0.2794) (xy 0.5334 0.2794)
			)
			(stroke
				(width 0)
				(type default)
			)
			(fill no)
			(layer "B.CrtYd")
		)
		(pad "1" smd rect
			(at -0.40005 0)
			(size 0.4572 0.508)
			(layers "B.Cu" "B.Mask" "B.Paste")
			(net "GND")
		)
		(pad "2" smd rect
			(at 0.40005 0)
			(size 0.4572 0.508)
			(layers "B.Cu" "B.Mask" "B.Paste")
			(net "P3V3_USB_NODE1")
		)
	)
	(footprint ""
		(layer "B.Cu")
		(at 171.180252 -100.98659)
		(property "Reference" "C371"
			(at 7.670038 0.253492 0)
			(unlocked yes)
			(layer "B.SilkS")
			(effects
				(font
					(size 0.7874 0.5842)
					(thickness 0.1524)
				)
				(justify left mirror)
			)
		)
		(property "Value" ""
			(at 0 0 0)
			(layer "B.Fab")
			(effects
				(font
					(size 1.27 1.27)
				)
				(justify mirror)
			)
		)
		(duplicate_pad_numbers_are_jumpers no)
		(fp_line
			(start -0.7874 -0.4064)
			(end -0.7874 0.4064)
			(stroke
				(width 0.1524)
				(type default)
			)
			(layer "B.SilkS")
		)
		(fp_line
			(start -0.7874 0.4064)
			(end 0.7874 0.4064)
			(stroke
				(width 0.1524)
				(type default)
			)
			(layer "B.SilkS")
		)
		(fp_line
			(start 0 0.381)
			(end 0 -0.381)
			(stroke
				(width 0.1524)
				(type default)
			)
			(layer "B.SilkS")
		)
		(fp_line
			(start 0.7874 -0.4064)
			(end -0.7874 -0.4064)
			(stroke
				(width 0.1524)
				(type default)
			)
			(layer "B.SilkS")
		)
		(fp_line
			(start 0.7874 0.4064)
			(end 0.7874 -0.4064)
			(stroke
				(width 0.1524)
				(type default)
			)
			(layer "B.SilkS")
		)
		(fp_poly
			(pts
				(xy 0.5334 0.254) (xy 0.635 0.254) (xy 0.635 0.2286) (xy 0.635 -0.254) (xy 0.5334 -0.254) (xy 0.5334 -0.2794)
				(xy -0.5334 -0.2794) (xy -0.5334 -0.254) (xy -0.635 -0.254) (xy -0.635 0.254) (xy -0.5334 0.254)
				(xy -0.5334 0.2794) (xy 0.508 0.2794) (xy 0.5334 0.2794)
			)
			(stroke
				(width 0)
				(type default)
			)
			(fill no)
			(layer "B.CrtYd")
		)
		(pad "1" smd rect
			(at -0.40005 0 180)
			(size 0.4572 0.508)
			(layers "B.Cu" "B.Mask" "B.Paste")
			(net "GND")
		)
		(pad "2" smd rect
			(at 0.40005 0 180)
			(size 0.4572 0.508)
			(layers "B.Cu" "B.Mask" "B.Paste")
			(net "P1V05_NODE1")
		)
	)
	(footprint ""
		(layer "B.Cu")
		(at 145.001996 -68.73113 -90)
		(property "Reference" "C337"
			(at -1.050036 -0.550926 270)
			(unlocked yes)
			(layer "B.SilkS")
			(effects
				(font
					(size 0.7874 0.5842)
					(thickness 0.1524)
				)
				(justify left mirror)
			)
		)
		(property "Value" ""
			(at 0 0 90)
			(layer "B.Fab")
			(effects
				(font
					(size 1.27 1.27)
				)
				(justify mirror)
			)
		)
		(duplicate_pad_numbers_are_jumpers no)
		(fp_line
			(start -0.7874 0.4064)
			(end 0.7874 0.4064)
			(stroke
				(width 0.1524)
				(type default)
			)
			(layer "B.SilkS")
		)
		(fp_line
			(start 0.7874 0.4064)
			(end 0.7874 -0.4064)
			(stroke
				(width 0.1524)
				(type default)
			)
			(layer "B.SilkS")
		)
		(fp_line
			(start 0 0.381)
			(end 0 -0.381)
			(stroke
				(width 0.1524)
				(type default)
			)
			(layer "B.SilkS")
		)
		(fp_line
			(start -0.7874 -0.4064)
			(end -0.7874 0.4064)
			(stroke
				(width 0.1524)
				(type default)
			)
			(layer "B.SilkS")
		)
		(fp_line
			(start 0.7874 -0.4064)
			(end -0.7874 -0.4064)
			(stroke
				(width 0.1524)
				(type default)
			)
			(layer "B.SilkS")
		)
		(fp_poly
			(pts
				(xy 0.5334 0.254) (xy 0.635 0.254) (xy 0.635 0.2286) (xy 0.635 -0.254) (xy 0.5334 -0.254) (xy 0.5334 -0.2794)
				(xy -0.5334 -0.2794) (xy -0.5334 -0.254) (xy -0.635 -0.254) (xy -0.635 0.254) (xy -0.5334 0.254)
				(xy -0.5334 0.2794) (xy 0.508 0.2794) (xy 0.5334 0.2794)
			)
			(stroke
				(width 0)
				(type default)
			)
			(fill no)
			(layer "B.CrtYd")
		)
		(pad "1" smd rect
			(at -0.40005 0 90)
			(size 0.4572 0.508)
			(layers "B.Cu" "B.Mask" "B.Paste")
			(net "P1V0_SATA")
		)
		(pad "2" smd rect
			(at 0.40005 0 90)
			(size 0.4572 0.508)
			(layers "B.Cu" "B.Mask" "B.Paste")
			(net "GND")
		)
	)
	(footprint ""
		(layer "B.Cu")
		(at 72.008492 -92.920058 90)
		(property "Reference" "R89"
			(at -1.399286 2.039874 270)
			(unlocked yes)
			(layer "B.SilkS")
			(effects
				(font
					(size 0.7874 0.5842)
					(thickness 0.1524)
				)
				(justify left mirror)
			)
		)
		(property "Value" ""
			(at 0 0 90)
			(layer "B.Fab")
			(effects
				(font
					(size 1.27 1.27)
				)
				(justify mirror)
			)
		)
		(duplicate_pad_numbers_are_jumpers no)
		(fp_line
			(start 0.7874 -0.4064)
			(end -0.7874 -0.4064)
			(stroke
				(width 0.1524)
				(type default)
			)
			(layer "B.SilkS")
		)
		(fp_line
			(start -0.7874 -0.4064)
			(end -0.7874 0.4064)
			(stroke
				(width 0.1524)
				(type default)
			)
			(layer "B.SilkS")
		)
		(fp_line
			(start 0.7874 0.4064)
			(end 0.7874 -0.4064)
			(stroke
				(width 0.1524)
				(type default)
			)
			(layer "B.SilkS")
		)
		(fp_line
			(start -0.7874 0.4064)
			(end 0.7874 0.4064)
			(stroke
				(width 0.1524)
				(type default)
			)
			(layer "B.SilkS")
		)
		(fp_poly
			(pts
				(xy 0.508 0.2794) (xy 0.508 0.2286) (xy 0.635 0.2286) (xy 0.635 -0.254) (xy 0.5334 -0.254) (xy 0.5334 -0.2794)
				(xy -0.5334 -0.2794) (xy -0.5334 -0.254) (xy -0.635 -0.254) (xy -0.635 0.254) (xy -0.5334 0.254)
				(xy -0.5334 0.2794)
			)
			(stroke
				(width 0)
				(type default)
			)
			(fill no)
			(layer "B.CrtYd")
		)
		(pad "1" smd rect
			(at -0.40005 0 270)
			(size 0.4572 0.508)
			(layers "B.Cu" "B.Mask" "B.Paste")
			(net "H_CPU_NODE1_ERR0")
		)
		(pad "2" smd rect
			(at 0.40005 0 270)
			(size 0.4572 0.508)
			(layers "B.Cu" "B.Mask" "B.Paste")
			(net "H_CPU_NODE1_ERR0_R")
		)
	)
	(footprint ""
		(layer "B.Cu")
		(at 180.213 -188.468 -90)
		(property "Reference" "C592"
			(at -1.4986 0.05207 270)
			(unlocked yes)
			(layer "B.SilkS")
			(effects
				(font
					(size 0.7874 0.5842)
					(thickness 0.1524)
				)
				(justify left mirror)
			)
		)
		(property "Value" ""
			(at 0 0 90)
			(layer "B.Fab")
			(effects
				(font
					(size 1.27 1.27)
				)
				(justify mirror)
			)
		)
		(duplicate_pad_numbers_are_jumpers no)
		(fp_line
			(start -0.7874 0.4064)
			(end 0.7874 0.4064)
			(stroke
				(width 0.1524)
				(type default)
			)
			(layer "B.SilkS")
		)
		(fp_line
			(start 0.7874 0.4064)
			(end 0.7874 -0.4064)
			(stroke
				(width 0.1524)
				(type default)
			)
			(layer "B.SilkS")
		)
		(fp_line
			(start 0 0.381)
			(end 0 -0.381)
			(stroke
				(width 0.1524)
				(type default)
			)
			(layer "B.SilkS")
		)
		(fp_line
			(start -0.7874 -0.4064)
			(end -0.7874 0.4064)
			(stroke
				(width 0.1524)
				(type default)
			)
			(layer "B.SilkS")
		)
		(fp_line
			(start 0.7874 -0.4064)
			(end -0.7874 -0.4064)
			(stroke
				(width 0.1524)
				(type default)
			)
			(layer "B.SilkS")
		)
		(fp_poly
			(pts
				(xy 0.5334 0.254) (xy 0.635 0.254) (xy 0.635 0.2286) (xy 0.635 -0.254) (xy 0.5334 -0.254) (xy 0.5334 -0.2794)
				(xy -0.5334 -0.2794) (xy -0.5334 -0.254) (xy -0.635 -0.254) (xy -0.635 0.254) (xy -0.5334 0.254)
				(xy -0.5334 0.2794) (xy 0.508 0.2794) (xy 0.5334 0.2794)
			)
			(stroke
				(width 0)
				(type default)
			)
			(fill no)
			(layer "B.CrtYd")
		)
		(pad "1" smd rect
			(at -0.40005 0 90)
			(size 0.4572 0.508)
			(layers "B.Cu" "B.Mask" "B.Paste")
			(net "POWER_SW1_PWR_CTR_12V_R")
		)
		(pad "2" smd rect
			(at 0.40005 0 90)
			(size 0.4572 0.508)
			(layers "B.Cu" "B.Mask" "B.Paste")
			(net "GND")
		)
	)
)
